(kicad_pcb
	(version 20260206)
	(generator "pcbnew")
	(generator_version "10.0")
	(general
		(thickness 1.6)
		(legacy_teardrops no)
	)
	(paper "A4")
	(title_block
		(title "Bryce Canyon_SCC_16316-1_OCP.brd")
		(comment 1 "Bryce Canyon / footprints 291-297 of 1561")
	)
	(layers
		(0 "F.Cu" signal "TOP")
		(4 "In1.Cu" signal "L2GND")
		(6 "In2.Cu" signal "L3")
		(8 "In3.Cu" signal "L4VCC")
		(10 "In4.Cu" signal "L5VCC")
		(12 "In5.Cu" signal "L6")
		(14 "In6.Cu" signal "L7GND")
		(2 "B.Cu" signal "BOTTOM")
		(9 "F.Adhes" user "F.Adhesive")
		(11 "B.Adhes" user "B.Adhesive")
		(13 "F.Paste" user "Package Geometry/Pastemask Top")
		(15 "B.Paste" user "Package Geometry/Pastemask Bottom")
		(5 "F.SilkS" user "Ref Des/Silkscreen Top")
		(7 "B.SilkS" user "Ref Des/Silkscreen Bottom")
		(1 "F.Mask" user "Board Geometry/Soldermask Top")
		(3 "B.Mask" user "Board Geometry/Soldermask Bottom")
		(17 "Dwgs.User" user "User.Drawings")
		(19 "Cmts.User" user "User.Comments")
		(21 "Eco1.User" user "User.Eco1")
		(23 "Eco2.User" user "User.Eco2")
		(25 "Edge.Cuts" user "Board Geometry/Outline")
		(27 "Margin" user)
		(31 "F.CrtYd" user "Package Geometry/Place Bound Top")
		(29 "B.CrtYd" user "Package Geometry/Place Bound Bottom")
		(35 "F.Fab" user "Ref Des/Assembly Top")
		(33 "B.Fab" user "Ref Des/Assembly Bottom")
	)
	(footprint ""
		(layer "F.Cu")
		(at 18.4912 -46.9646 180)
		(property "Reference" "R550"
			(at 0 0 180)
			(layer "F.SilkS")
			(hide yes)
			(effects
				(font
					(size 1.27 1.27)
				)
			)
		)
		(property "Value" "49K9R2F-L-GP"
			(at 0.064008 -3.993896 180)
			(unlocked yes)
			(layer "F.Fab")
			(hide yes)
			(effects
				(font
					(size 1.016 1.016)
					(thickness 0.1524)
				)
			)
		)
		(property "Device Type" "R402H16"
			(at 0.064008 -5.517896 180)
			(unlocked yes)
			(layer "F.Fab")
			(hide yes)
			(effects
				(font
					(size 1.016 1.016)
					(thickness 0.1524)
				)
			)
		)
		(duplicate_pad_numbers_are_jumpers no)
		(fp_line
			(start 0.508 -0.9398)
			(end -0.508 -0.9398)
			(stroke
				(width 0.1524)
				(type default)
			)
			(layer "F.SilkS")
		)
		(fp_line
			(start -0.508 -0.9398)
			(end -0.508 0.9398)
			(stroke
				(width 0.1524)
				(type default)
			)
			(layer "F.SilkS")
		)
		(fp_rect
			(start -0.508 0.9398)
			(end 0.508 -0.9398)
			(stroke
				(width 0)
				(type default)
			)
			(fill no)
			(layer "F.CrtYd")
		)
		(fp_rect
			(start -0.508 0.9398)
			(end 0.508 -0.9398)
			(stroke
				(width 0)
				(type default)
			)
			(fill no)
			(layer "F.Fab")
		)
		(pad "1" smd custom
			(at 0 -0.4445 180)
			(size 0.1397 0.1397)
			(layers "F.Cu" "F.Mask" "F.Paste")
			(net "P12V_MAIN")
			(options
				(clearance outline)
				(anchor circle)
			)
			(primitives
				(gr_poly
					(pts
						(arc
							(start -0.1778 -0.2794)
							(mid -0.249642 -0.249642)
							(end -0.2794 -0.1778)
						)
						(arc
							(start -0.2794 0.1778)
							(mid -0.249642 0.249642)
							(end -0.1778 0.2794)
						)
						(arc
							(start 0.1778 0.2794)
							(mid 0.249642 0.249642)
							(end 0.2794 0.1778)
						)
						(arc
							(start 0.2794 -0.1778)
							(mid 0.249642 -0.249642)
							(end 0.1778 -0.2794)
						)
					)
					(width 0)
					(fill yes)
				)
			)
		)
		(pad "2" smd custom
			(at 0 0.4445 180)
			(size 0.1397 0.1397)
			(layers "F.Cu" "F.Mask" "F.Paste")
			(net "MB0_CM_UV_R")
			(options
				(clearance outline)
				(anchor circle)
			)
			(primitives
				(gr_poly
					(pts
						(arc
							(start -0.1778 -0.2794)
							(mid -0.249642 -0.249642)
							(end -0.2794 -0.1778)
						)
						(arc
							(start -0.2794 0.1778)
							(mid -0.249642 0.249642)
							(end -0.1778 0.2794)
						)
						(arc
							(start 0.1778 0.2794)
							(mid 0.249642 0.249642)
							(end 0.2794 0.1778)
						)
						(arc
							(start 0.2794 -0.1778)
							(mid 0.249642 -0.249642)
							(end 0.1778 -0.2794)
						)
					)
					(width 0)
					(fill yes)
				)
			)
		)
	)
	(footprint ""
		(layer "F.Cu")
		(at 181.1401 -114.80673)
		(property "Reference" "C605"
			(at 0 0 0)
			(layer "F.SilkS")
			(hide yes)
			(effects
				(font
					(size 1.27 1.27)
				)
			)
		)
		(property "Value" "SC1KP50V2KX-1GP"
			(at 1.1811 -2.7051 0)
			(unlocked yes)
			(layer "F.Fab")
			(hide yes)
			(effects
				(font
					(size 1.016 1.016)
					(thickness 0.1524)
				)
			)
		)
		(property "Device Type" "C402H22"
			(at 1.1811 -4.2291 0)
			(unlocked yes)
			(layer "F.Fab")
			(hide yes)
			(effects
				(font
					(size 1.016 1.016)
					(thickness 0.1524)
				)
			)
		)
		(duplicate_pad_numbers_are_jumpers no)
		(fp_rect
			(start -0.4318 0.9525)
			(end 0.4318 -0.9525)
			(stroke
				(width 0)
				(type default)
			)
			(fill no)
			(layer "F.CrtYd")
		)
		(fp_rect
			(start -0.4318 0.9525)
			(end 0.4318 -0.9525)
			(stroke
				(width 0)
				(type default)
			)
			(fill no)
			(layer "F.Fab")
		)
		(pad "1" smd custom
			(at 0 -0.4445)
			(size 0.1524 0.1524)
			(layers "F.Cu" "F.Mask" "F.Paste")
			(net "P1V8_E_OUT")
			(options
				(clearance outline)
				(anchor circle)
			)
			(primitives
				(gr_poly
					(pts
						(arc
							(start 0.3048 -0.2032)
							(mid 0.275042 -0.275042)
							(end 0.2032 -0.3048)
						)
						(arc
							(start -0.2032 -0.3048)
							(mid -0.275042 -0.275042)
							(end -0.3048 -0.2032)
						)
						(arc
							(start -0.3048 0.2032)
							(mid -0.275042 0.275042)
							(end -0.2032 0.3048)
						)
						(arc
							(start 0.2032 0.3048)
							(mid 0.275042 0.275042)
							(end 0.3048 0.2032)
						)
					)
					(width 0)
					(fill yes)
				)
			)
		)
		(pad "2" smd custom
			(at 0 0.4445)
			(size 0.1524 0.1524)
			(layers "F.Cu" "F.Mask" "F.Paste")
			(net "P1V8_E_FB")
			(options
				(clearance outline)
				(anchor circle)
			)
			(primitives
				(gr_poly
					(pts
						(arc
							(start 0.3048 -0.2032)
							(mid 0.275042 -0.275042)
							(end 0.2032 -0.3048)
						)
						(arc
							(start -0.2032 -0.3048)
							(mid -0.275042 -0.275042)
							(end -0.3048 -0.2032)
						)
						(arc
							(start -0.3048 0.2032)
							(mid -0.275042 0.275042)
							(end -0.2032 0.3048)
						)
						(arc
							(start 0.2032 0.3048)
							(mid 0.275042 0.275042)
							(end 0.3048 0.2032)
						)
					)
					(width 0)
					(fill yes)
				)
			)
		)
	)
	(footprint ""
		(layer "F.Cu")
		(at 58.928 -17.272 90)
		(property "Reference" "R544"
			(at 0 0 90)
			(layer "F.SilkS")
			(hide yes)
			(effects
				(font
					(size 1.27 1.27)
				)
			)
		)
		(property "Value" "0R2J-2-GP"
			(at 0.064008 -3.993896 90)
			(unlocked yes)
			(layer "F.Fab")
			(hide yes)
			(effects
				(font
					(size 1.016 1.016)
					(thickness 0.1524)
				)
			)
		)
		(property "Device Type" "R402H16"
			(at 0.064008 -5.517896 90)
			(unlocked yes)
			(layer "F.Fab")
			(hide yes)
			(effects
				(font
					(size 1.016 1.016)
					(thickness 0.1524)
				)
			)
		)
		(duplicate_pad_numbers_are_jumpers no)
		(fp_line
			(start 0.508 -0.9398)
			(end -0.508 -0.9398)
			(stroke
				(width 0.1524)
				(type default)
			)
			(layer "F.SilkS")
		)
		(fp_line
			(start -0.508 -0.9398)
			(end -0.508 0.9398)
			(stroke
				(width 0.1524)
				(type default)
			)
			(layer "F.SilkS")
		)
		(fp_rect
			(start -0.508 0.9398)
			(end 0.508 -0.9398)
			(stroke
				(width 0)
				(type default)
			)
			(fill no)
			(layer "F.CrtYd")
		)
		(fp_rect
			(start -0.508 0.9398)
			(end 0.508 -0.9398)
			(stroke
				(width 0)
				(type default)
			)
			(fill no)
			(layer "F.Fab")
		)
		(pad "1" smd custom
			(at 0 -0.4445 90)
			(size 0.1397 0.1397)
			(layers "F.Cu" "F.Mask" "F.Paste")
			(net "SCC_STBY_PWR_EN")
			(options
				(clearance outline)
				(anchor circle)
			)
			(primitives
				(gr_poly
					(pts
						(arc
							(start -0.1778 -0.2794)
							(mid -0.249642 -0.249642)
							(end -0.2794 -0.1778)
						)
						(arc
							(start -0.2794 0.1778)
							(mid -0.249642 0.249642)
							(end -0.1778 0.2794)
						)
						(arc
							(start 0.1778 0.2794)
							(mid 0.249642 0.249642)
							(end 0.2794 0.1778)
						)
						(arc
							(start 0.2794 -0.1778)
							(mid 0.249642 -0.249642)
							(end 0.1778 -0.2794)
						)
					)
					(width 0)
					(fill yes)
				)
			)
		)
		(pad "2" smd custom
			(at 0 0.4445 90)
			(size 0.1397 0.1397)
			(layers "F.Cu" "F.Mask" "F.Paste")
			(net "SCC_STBY_PWR_BUF_EN")
			(options
				(clearance outline)
				(anchor circle)
			)
			(primitives
				(gr_poly
					(pts
						(arc
							(start -0.1778 -0.2794)
							(mid -0.249642 -0.249642)
							(end -0.2794 -0.1778)
						)
						(arc
							(start -0.2794 0.1778)
							(mid -0.249642 0.249642)
							(end -0.1778 0.2794)
						)
						(arc
							(start 0.1778 0.2794)
							(mid 0.249642 0.249642)
							(end 0.2794 0.1778)
						)
						(arc
							(start 0.2794 -0.1778)
							(mid 0.249642 -0.249642)
							(end 0.1778 -0.2794)
						)
					)
					(width 0)
					(fill yes)
				)
			)
		)
	)
	(footprint ""
		(layer "F.Cu")
		(at 163.298378 -96.847406 180)
		(property "Reference" "C619"
			(at 0 0 180)
			(layer "F.SilkS")
			(hide yes)
			(effects
				(font
					(size 1.27 1.27)
				)
			)
		)
		(property "Value" "SC1U25V3KX-GP"
			(at 0 -2.8194 180)
			(unlocked yes)
			(layer "F.Fab")
			(hide yes)
			(effects
				(font
					(size 1.016 1.016)
					(thickness 0.1524)
				)
			)
		)
		(property "Device Type" "C603H36"
			(at 0 -4.3434 180)
			(unlocked yes)
			(layer "F.Fab")
			(hide yes)
			(effects
				(font
					(size 1.016 1.016)
					(thickness 0.1524)
				)
			)
		)
		(duplicate_pad_numbers_are_jumpers no)
		(fp_line
			(start 0.508 0)
			(end -0.508 0)
			(stroke
				(width 0.2032)
				(type default)
			)
			(layer "F.SilkS")
		)
		(fp_rect
			(start -0.5842 1.3335)
			(end 0.5842 -1.3335)
			(stroke
				(width 0)
				(type default)
			)
			(fill no)
			(layer "F.CrtYd")
		)
		(fp_rect
			(start -0.5842 1.3335)
			(end 0.5842 -1.3335)
			(stroke
				(width 0)
				(type default)
			)
			(fill no)
			(layer "F.Fab")
		)
		(pad "1" smd custom
			(at 0 -0.762 180)
			(size 0.2159 0.2159)
			(layers "F.Cu" "F.Mask" "F.Paste")
			(net "VT235_AVDD")
			(options
				(clearance outline)
				(anchor circle)
			)
			(primitives
				(gr_poly
					(pts
						(arc
							(start -0.3302 -0.4318)
							(mid -0.402042 -0.402042)
							(end -0.4318 -0.3302)
						)
						(arc
							(start -0.4318 0.3302)
							(mid -0.402042 0.402042)
							(end -0.3302 0.4318)
						)
						(arc
							(start 0.3302 0.4318)
							(mid 0.402042 0.402042)
							(end 0.4318 0.3302)
						)
						(arc
							(start 0.4318 -0.3302)
							(mid 0.402042 -0.402042)
							(end 0.3302 -0.4318)
						)
					)
					(width 0)
					(fill yes)
				)
			)
		)
		(pad "2" smd custom
			(at 0 0.762 180)
			(size 0.2159 0.2159)
			(layers "F.Cu" "F.Mask" "F.Paste")
			(net "AGND_P0V975")
			(options
				(clearance outline)
				(anchor circle)
			)
			(primitives
				(gr_poly
					(pts
						(arc
							(start -0.3302 -0.4318)
							(mid -0.402042 -0.402042)
							(end -0.4318 -0.3302)
						)
						(arc
							(start -0.4318 0.3302)
							(mid -0.402042 0.402042)
							(end -0.3302 0.4318)
						)
						(arc
							(start 0.3302 0.4318)
							(mid 0.402042 0.402042)
							(end 0.4318 0.3302)
						)
						(arc
							(start 0.4318 -0.3302)
							(mid 0.402042 -0.402042)
							(end 0.3302 -0.4318)
						)
					)
					(width 0)
					(fill yes)
				)
			)
		)
	)
	(footprint ""
		(layer "F.Cu")
		(at 191.994282 -80.564736 -90)
		(property "Reference" "R369"
			(at 0 0 270)
			(layer "F.SilkS")
			(hide yes)
			(effects
				(font
					(size 1.27 1.27)
				)
			)
		)
		(property "Value" "4K7R2F-GP"
			(at 0.064008 -3.993896 270)
			(unlocked yes)
			(layer "F.Fab")
			(hide yes)
			(effects
				(font
					(size 1.016 1.016)
					(thickness 0.1524)
				)
			)
		)
		(property "Device Type" "R402H16"
			(at 0.064008 -5.517896 270)
			(unlocked yes)
			(layer "F.Fab")
			(hide yes)
			(effects
				(font
					(size 1.016 1.016)
					(thickness 0.1524)
				)
			)
		)
		(duplicate_pad_numbers_are_jumpers no)
		(fp_line
			(start -0.508 -0.9398)
			(end -0.508 0.9398)
			(stroke
				(width 0.1524)
				(type default)
			)
			(layer "F.SilkS")
		)
		(fp_line
			(start 0.508 -0.9398)
			(end -0.508 -0.9398)
			(stroke
				(width 0.1524)
				(type default)
			)
			(layer "F.SilkS")
		)
		(fp_rect
			(start -0.508 0.9398)
			(end 0.508 -0.9398)
			(stroke
				(width 0)
				(type default)
			)
			(fill no)
			(layer "F.CrtYd")
		)
		(fp_rect
			(start -0.508 0.9398)
			(end 0.508 -0.9398)
			(stroke
				(width 0)
				(type default)
			)
			(fill no)
			(layer "F.Fab")
		)
		(pad "1" smd custom
			(at 0 -0.4445 270)
			(size 0.1397 0.1397)
			(layers "F.Cu" "F.Mask" "F.Paste")
			(net "TEMP2_A2")
			(options
				(clearance outline)
				(anchor circle)
			)
			(primitives
				(gr_poly
					(pts
						(arc
							(start -0.1778 -0.2794)
							(mid -0.249642 -0.249642)
							(end -0.2794 -0.1778)
						)
						(arc
							(start -0.2794 0.1778)
							(mid -0.249642 0.249642)
							(end -0.1778 0.2794)
						)
						(arc
							(start 0.1778 0.2794)
							(mid 0.249642 0.249642)
							(end 0.2794 0.1778)
						)
						(arc
							(start 0.2794 -0.1778)
							(mid 0.249642 -0.249642)
							(end 0.1778 -0.2794)
						)
					)
					(width 0)
					(fill yes)
				)
			)
		)
		(pad "2" smd custom
			(at 0 0.4445 270)
			(size 0.1397 0.1397)
			(layers "F.Cu" "F.Mask" "F.Paste")
			(net "GND")
			(options
				(clearance outline)
				(anchor circle)
			)
			(primitives
				(gr_poly
					(pts
						(arc
							(start -0.1778 -0.2794)
							(mid -0.249642 -0.249642)
							(end -0.2794 -0.1778)
						)
						(arc
							(start -0.2794 0.1778)
							(mid -0.249642 0.249642)
							(end -0.1778 0.2794)
						)
						(arc
							(start 0.1778 0.2794)
							(mid 0.249642 0.249642)
							(end 0.2794 0.1778)
						)
						(arc
							(start 0.2794 -0.1778)
							(mid 0.249642 -0.249642)
							(end 0.1778 -0.2794)
						)
					)
					(width 0)
					(fill yes)
				)
			)
		)
	)
	(footprint ""
		(layer "F.Cu")
		(at 6.731 -40.259)
		(property "Reference" "C737"
			(at 0 0 0)
			(layer "F.SilkS")
			(hide yes)
			(effects
				(font
					(size 1.27 1.27)
				)
			)
		)
		(property "Value" "SCD022U25V2KX-GP"
			(at 1.1811 -2.7051 0)
			(unlocked yes)
			(layer "F.Fab")
			(hide yes)
			(effects
				(font
					(size 1.016 1.016)
					(thickness 0.1524)
				)
			)
		)
		(property "Device Type" "C402H22"
			(at 1.1811 -4.2291 0)
			(unlocked yes)
			(layer "F.Fab")
			(hide yes)
			(effects
				(font
					(size 1.016 1.016)
					(thickness 0.1524)
				)
			)
		)
		(duplicate_pad_numbers_are_jumpers no)
		(fp_rect
			(start -0.4318 0.9525)
			(end 0.4318 -0.9525)
			(stroke
				(width 0)
				(type default)
			)
			(fill no)
			(layer "F.CrtYd")
		)
		(fp_rect
			(start -0.4318 0.9525)
			(end 0.4318 -0.9525)
			(stroke
				(width 0)
				(type default)
			)
			(fill no)
			(layer "F.Fab")
		)
		(pad "1" smd custom
			(at 0 -0.4445)
			(size 0.1524 0.1524)
			(layers "F.Cu" "F.Mask" "F.Paste")
			(net "MB0_12V_CTRL_GATE1_R")
			(options
				(clearance outline)
				(anchor circle)
			)
			(primitives
				(gr_poly
					(pts
						(arc
							(start 0.3048 -0.2032)
							(mid 0.275042 -0.275042)
							(end 0.2032 -0.3048)
						)
						(arc
							(start -0.2032 -0.3048)
							(mid -0.275042 -0.275042)
							(end -0.3048 -0.2032)
						)
						(arc
							(start -0.3048 0.2032)
							(mid -0.275042 0.275042)
							(end -0.2032 0.3048)
						)
						(arc
							(start 0.2032 0.3048)
							(mid 0.275042 0.275042)
							(end 0.3048 0.2032)
						)
					)
					(width 0)
					(fill yes)
				)
			)
		)
		(pad "2" smd custom
			(at 0 0.4445)
			(size 0.1524 0.1524)
			(layers "F.Cu" "F.Mask" "F.Paste")
			(net "GND")
			(options
				(clearance outline)
				(anchor circle)
			)
			(primitives
				(gr_poly
					(pts
						(arc
							(start 0.3048 -0.2032)
							(mid 0.275042 -0.275042)
							(end 0.2032 -0.3048)
						)
						(arc
							(start -0.2032 -0.3048)
							(mid -0.275042 -0.275042)
							(end -0.3048 -0.2032)
						)
						(arc
							(start -0.3048 0.2032)
							(mid -0.275042 0.275042)
							(end -0.2032 0.3048)
						)
						(arc
							(start 0.2032 0.3048)
							(mid 0.275042 0.275042)
							(end 0.3048 0.2032)
						)
					)
					(width 0)
					(fill yes)
				)
			)
		)
	)
	(footprint ""
		(layer "F.Cu")
		(at 158.88081 -44.823634 -90)
		(property "Reference" "X2"
			(at 0 0 270)
			(layer "F.SilkS")
			(hide yes)
			(effects
				(font
					(size 1.27 1.27)
				)
			)
		)
		(property "Value" "XTAL-25MHZ-295-GP"
			(at -4.4958 -3.3782 270)
			(unlocked yes)
			(layer "F.Fab")
			(hide yes)
			(effects
				(font
					(size 1.016 1.016)
					(thickness 0.1524)
				)
			)
		)
		(property "Device Type" "SMD-OSC38H20"
			(at -4.4958 -4.9022 270)
			(unlocked yes)
			(layer "F.Fab")
			(hide yes)
			(effects
				(font
					(size 1.016 1.016)
					(thickness 0.1524)
				)
			)
		)
		(duplicate_pad_numbers_are_jumpers no)
		(fp_line
			(start -1.668272 1.2065)
			(end -1.668272 0.462788)
			(stroke
				(width 0.3302)
				(type default)
			)
			(layer "F.SilkS")
		)
		(fp_line
			(start -0.659384 1.2065)
			(end -1.668272 1.2065)
			(stroke
				(width 0.3302)
				(type default)
			)
			(layer "F.SilkS")
		)
		(fp_line
			(start -1.5748 1.1176)
			(end -1.5748 -1.1176)
			(stroke
				(width 0.1524)
				(type default)
			)
			(layer "F.SilkS")
		)
		(fp_line
			(start 1.5748 1.1176)
			(end -1.5748 1.1176)
			(stroke
				(width 0.1524)
				(type default)
			)
			(layer "F.SilkS")
		)
		(fp_line
			(start -1.5748 -1.1176)
			(end 1.5748 -1.1176)
			(stroke
				(width 0.1524)
				(type default)
			)
			(layer "F.SilkS")
		)
		(fp_line
			(start 1.5748 -1.1176)
			(end 1.5748 1.1176)
			(stroke
				(width 0.1524)
				(type default)
			)
			(layer "F.SilkS")
		)
		(fp_poly
			(pts
				(xy -2.286 1.1557) (xy -2.286 -0.1143) (xy -1.651 0.5207)
			)
			(stroke
				(width 0)
				(type default)
			)
			(fill yes)
			(layer "F.SilkS")
		)
		(fp_rect
			(start -1.0033 0.8001)
			(end 1.0033 -0.8001)
			(stroke
				(width 0)
				(type default)
			)
			(fill no)
			(layer "F.CrtYd")
		)
		(fp_poly
			(pts
				(xy -1.8288 1.3716) (xy -1.8288 -1.3716) (xy 1.8288 -1.3716) (xy 1.8288 -0.0127) (xy 1.0033 -0.0127)
				(xy 1.0033 -0.8001) (xy -1.0033 -0.8001) (xy -1.0033 0.8001) (xy 1.0033 0.8001) (xy 1.0033 0) (xy 1.8288 0)
				(xy 1.8288 1.3716)
			)
			(stroke
				(width 0)
				(type default)
			)
			(fill no)
			(layer "F.CrtYd")
		)
		(fp_rect
			(start -1.8288 1.3716)
			(end 1.8288 -1.3716)
			(stroke
				(width 0)
				(type default)
			)
			(fill no)
			(layer "F.Fab")
		)
		(pad "1" smd rect
			(at -0.769112 0.495046 270)
			(size 1.0922 0.7366)
			(layers "F.Cu" "F.Mask" "F.Paste")
			(net "REF_CLK")
		)
		(pad "2" smd rect
			(at 0.769112 0.495046 270)
			(size 1.0922 0.7366)
			(layers "F.Cu" "F.Mask" "F.Paste")
			(net "GND")
		)
		(pad "3" smd rect
			(at 0.769112 -0.495046 270)
			(size 1.0922 0.7366)
			(layers "F.Cu" "F.Mask" "F.Paste")
			(net "IOC_REF_CLK_P")
		)
		(pad "4" smd rect
			(at -0.769112 -0.495046 270)
			(size 1.0922 0.7366)
			(layers "F.Cu" "F.Mask" "F.Paste")
			(net "GND")
		)
		(zone
			(layer "F.Cu")
			(hatch none 0.5)
			(connect_pads
				(clearance 0)
			)
			(min_thickness 0.25)
			(keepout
				(tracks not_allowed)
				(vias allowed)
				(pads allowed)
				(copperpour not_allowed)
				(footprints allowed)
			)
			(placement
				(enabled no)
				(sheetname "")
			)
			(fill
				(thermal_gap 0.5)
				(thermal_bridge_width 0.5)
				(island_removal_mode 0)
			)
			(polygon
				(pts
					(xy 158.017464 -45.046646) (xy 158.754064 -45.046646) (xy 158.754064 -46.138846) (xy 159.007556 -46.138846)
					(xy 159.007556 -45.046646) (xy 159.744156 -45.046646) (xy 159.744156 -44.600622) (xy 159.007556 -44.600622)
					(xy 159.007556 -43.508422) (xy 158.754064 -43.508422) (xy 158.754064 -44.600622) (xy 158.017464 -44.600622)
				)
			)
		)
		(zone
			(layer "F.Cu")
			(hatch none 0.5)
			(connect_pads
				(clearance 0)
			)
			(min_thickness 0.25)
			(keepout
				(tracks allowed)
				(vias not_allowed)
				(pads allowed)
				(copperpour not_allowed)
				(footprints allowed)
			)
			(placement
				(enabled no)
				(sheetname "")
			)
			(fill
				(thermal_gap 0.5)
				(thermal_bridge_width 0.5)
				(island_removal_mode 0)
			)
			(polygon
				(pts
					(xy 158.017464 -45.046646) (xy 158.754064 -45.046646) (xy 158.754064 -46.138846) (xy 159.007556 -46.138846)
					(xy 159.007556 -45.046646) (xy 159.744156 -45.046646) (xy 159.744156 -44.600622) (xy 159.007556 -44.600622)
					(xy 159.007556 -43.508422) (xy 158.754064 -43.508422) (xy 158.754064 -44.600622) (xy 158.017464 -44.600622)
				)
			)
		)
	)
)
